FILE_TYPE = CONNECTIVITY;
{Allegro Design Entry HDL 17.2-2016 S081 (4005846) 1/11/2022}
"PAGE_NUMBER" = 270;
0"NC";
1"P12V_AUX\g";
2"P3V3_AUX\g";
3"P3V3_AUX\g";
4"P3V3_AUX\g";
5"PVCCFA_EHV_FIVRA_CPU1\g";
6"PVCCIN_CPU1\g";
7"P3V3_AUX\g";
8"PVNN_TERM_CPU1\g";
9"P3V3_AUX\g";
10"GND\g";
11"GND\g";
12"GND\g";
13"GND\g";
14"GND\g";
15"GND\g";
16"GND\g";
17"GND\g";
18"GND\g";
19"GND\g";
20"GND\g";
21"GND\g";
22"GND\g";
23"GND\g";
24"GND\g";
25"GND\g";
26"GND\g";
27"GND\g";
28"GND\g";
29"VSENSE_PVCCIN_CPU1_DN";
30"PVCCIN_CPU1_IMON2";
31"PVCCIN_CPU1_PWM2";
32"SMB_CLK_PVCCIN_CPU1";
33"SMB_VR_3V3AUX_SCL_R3";
34"PVCCIN_CPU1_VR_FAULT";
35"IRQ_PVCCIN_CPU1_VRHOT_R_N";
36"PVCCIN_CPU1_PIN_ALERT";
37"IRQ_PVCCIN_CPU1_VRHOT_N";
38"VSENSE_PVCCFA_EHV_FIVRA_CPU1_DN";
39"PVCCIN_CPU1_VREF";
40"PVCCIN_CPU1_ADDR";
41"VSENSE_PVCCFA_EHV_FIVRA_CPU1_DP";
42"FM_PVCCFA_EHV_FIVRA_CPU1_EN";
43"PWRGD_PVCCFA_EHV_FIVRA_CPU1";
44"SH_PVCCFA_EHV_FIVRA_CPU1";
45"PVCCIN_CPU1_CSPIN";
46"PVCCIN_CPU1_VIN_CSNIN";
47"PWRGD_PVCCFA_EHV_FIVRA_CPU1_R";
48"SH_PVCCFA_EHV_FIVRA_CPU1_R";
49"VSENSE_PVCCIN_CPU1_DP";
50"SVID_ALERT0_CPU1_R_N";
51"PWRGD_PVCCIN_CPU1";
52"FM_PVCCIN_CPU1_EN";
53"SVID_CLK0_CPU1_R";
54"SVID_DIO0_CPU1_R";
55"PWRGD_PVCCIN_CPU1_R";
56"SVID_CLK_PVCCIN_CPU1_R";
57"SVID_DIO_PVCCIN_CPU1_R";
58"SVID_ALERT_PVCCIN_CPU1_R";
59"SMB_VR_3V3AUX_SDA_R3";
60"NC_PVCCIN_CPU1_SMB_ALERT";
61"SMB_DIO_PVCCIN_CPU1";
62"PVCCIN_CPU1_EN_R";
63"PVCCIN_CPU1_ATSEN";
64"PVCCFA_EHV_FIVRA_CPU1_PWM4";
65"PVCCFA_EHV_FIVRA_CPU1_PWM1";
66"PVCCIN_CPU1_PWM8";
67"PVCCIN_CPU1_IMON8";
68"PVCCIN_CPU1_IMON7";
69"PVCCFA_EHV_FIVRA_CPU1_IMON1";
70"PVCCFA_EHV_FIVRA_CPU1_IMON2";
71"PVCCFA_EHV_FIVRA_CPU1_PWM2";
72"PVCCFA_EHV_FIVRA_CPU1_PWM3";
73"PVCCFA_EHV_FIVRA_CPU1_IMON3";
74"PVCCFA_EHV_FIVRA_CPU1_IMON4";
75"PVCCFA_EHV_FIVRA_CPU1_BTSEN";
76"SVID_DIO0_CPU1_R"CDS_PHYS_NET_NAME"SVID_DIO0_CPU1_R";
77"SVID_CLK0_CPU1_R"CDS_PHYS_NET_NAME"SVID_CLK0_CPU1_R";
78"SVID_ALERT0_CPU1_R_N"CDS_PHYS_NET_NAME"SVID_ALERT0_CPU1_R_N";
79"PVCCIN_CPU1_PWM6";
80"PVCCIN_CPU1_IMON5";
81"PVCCIN_CPU1_PWM5";
82"PVCCIN_CPU1_PWM7";
83"PVCCIN_CPU1_PWM1";
84"PVCCIN_CPU1_IMON1";
85"PVCCIN_CPU1_IMON6";
86"PVCCIN_CPU1_PWM4";
87"PVCCIN_CPU1_PWM3";
88"PVCCIN_CPU1_IMON4";
89"SH_PVCCIN_CPU1";
90"SH_PVCCIN_CPU1_R";
91"PVCCIN_CPU1_IMON3";
92"PVCCIN_CPU1_VREF";
93"PVCCIN_CPU1_VCC";
94"PVCCFA_EHV_FIVRA_CPU1_EN_R";
%"Q_RES"
"1","(3925,-1075)","0","pure_quanta","I100";
;
PART_NUMBER"CS04992FB07"
MATERIAL"CHIP"
VALUE"49.9"
TOLERANCE"1%"
LOCATION"R2554"
PACK_TYPE"0402LF"
WATTAGE"1/16W"
CDS_LIB"pure_quanta"
$SEC"1"
CDS_SEC"1";
"B"
$PN"2"8;
"A"
$PN"1"77;
%"Q_RES"
"1","(3925,-1225)","0","pure_quanta","I101";
;
PART_NUMBER"CS04992FB07"
TOLERANCE"1%"
MATERIAL"EMPTY"
VALUE"49.9"
LOCATION"R2555"
PACK_TYPE"0402LF"
WATTAGE"1/16W"
CDS_LIB"pure_quanta"
$SEC"1"
CDS_SEC"1";
"B"
$PN"2"8;
"A"
$PN"1"78;
%"UNIVERSAL_GND"
"1","(3700,-600)","0","logical_power","I102";
;
HDL_POWER"GND"
CDS_LIB"logical_power";
"A"26;
%"Q_CAP"
"1","(3700,-300)","0","pure_quanta","I103";
;
PART_NUMBER"CH610KME907"
MATERIAL"EMPTY"
TOLERANCE"20%"
VALUE"10UF"
VOLTAGE"4V"
PACK_TYPE"C0603"
LOCATION"C2448"
CDS_LIB"pure_quanta"
LOCATION"C2448"
$SEC"1"
CDS_SEC"1";
"B"
$PN"2"26;
"A"
$PN"1"8;
%"Q_CAP"
"1","(4025,-325)","0","pure_quanta","I104";
;
PART_NUMBER"CH4106K1B01"
TOLERANCE"10%"
MATERIAL"X7R"
PACK_TYPE"C0402"
VOLTAGE"50V"
VALUE"100NF"
LOCATION"C2449"
CDS_LIB"pure_quanta"
LOCATION"C2449"
$SEC"1"
CDS_SEC"1";
"B"
$PN"2"26;
"A"
$PN"1"8;
%"VCC15"
"1","(4425,-25)","0","logical_power","I105";
;
HDL_POWER"PVNN_TERM_CPU1"
CDS_LIB"logical_power";
"A"8;
%"Q_CAP"
"1","(1450,2350)","0","pure_quanta","I119";
;
PART_NUMBER"CH6101MEB03"
VOLTAGE"6.3V"
TOLERANCE"20%"
MATERIAL"X6S"
PACK_TYPE"C0402"
VALUE"10UF"
LOCATION"PC553"
CDS_LIB"pure_quanta"
LOCATION"PC553"
$SEC"1"
CDS_SEC"1";
"B"
$PN"2"27;
"A"
$PN"1"92;
%"Q_RES"
"1","(-3100,-600)","0","pure_quanta","I12";
;
PART_NUMBER"CS11002FB07"
MATERIAL"CHIP"
TOLERANCE"1%"
VALUE"100"
WATTAGE"1/16W"
PACK_TYPE"0402LF"
LOCATION"PR560"
CDS_LIB"pure_quanta"
$SEC"1"
CDS_SEC"1";
"B"
$PN"2"11;
"A"
$PN"1"38;
%"Q_CAP"
"1","(1450,2825)","0","pure_quanta","I120";
;
PART_NUMBER"CH4106K1B01"
VALUE"100NF"
VOLTAGE"50V"
TOLERANCE"10%"
MATERIAL"EMPTY"
PACK_TYPE"C0402"
LOCATION"PC552"
CDS_LIB"pure_quanta"
LOCATION"PC552"
$SEC"1"
CDS_SEC"1";
"B"
$PN"2"28;
"A"
$PN"1"93;
%"Q_CAP"
"1","(1850,2350)","0","pure_quanta","I121";
;
PART_NUMBER"CH5103KEB01"
MATERIAL"X6S"
PACK_TYPE"C0402"
VALUE"1UF"
TOLERANCE"10%"
VOLTAGE"16V"
LOCATION"PC1194"
CDS_LIB"pure_quanta"
$SEC"1"
CDS_SEC"1";
"B"
$PN"2"27;
"A"
$PN"1"92;
%"Q_CAP"
"1","(1850,2825)","0","pure_quanta","I122";
;
PART_NUMBER"CH5103KEB01"
MATERIAL"X6S"
VOLTAGE"16V"
VALUE"1UF"
TOLERANCE"10%"
PACK_TYPE"C0402"
LOCATION"PC555"
CDS_LIB"pure_quanta"
LOCATION"PC555"
$SEC"1"
CDS_SEC"1";
"B"
$PN"2"28;
"A"
$PN"1"93;
%"UNIVERSAL_GND"
"1","(2300,2150)","3","logical_power","I123";
;
HDL_POWER"GND"
CDS_LIB"logical_power";
"A"27;
%"UNIVERSAL_GND"
"1","(2300,2625)","3","logical_power","I125";
;
HDL_POWER"GND"
CDS_LIB"logical_power";
"A"28;
%"Q_RES"
"1","(2175,3025)","0","pure_quanta","I126";
;
PART_NUMBER"CS-1002FB04"
TOLERANCE"1%"
VALUE"1"
WATTAGE"1/16W"
PACK_TYPE"0402LF"
MATERIAL"CHIP"
LOCATION"PR323"
CDS_LIB"pure_quanta"
LOCATION"PR323"
$SEC"1"
CDS_SEC"1";
"B"
$PN"2"9;
"A"
$PN"1"93;
%"VCC15"
"1","(2650,3150)","0","logical_power","I127";
;
HDL_POWER"P3V3_AUX"
CDS_LIB"logical_power";
"A"9;
%"Q_CAP"
"1","(1100,2825)","0","pure_quanta","I128";
;
PART_NUMBER"CH4104K1B00"
PACK_TYPE"0402"
MATERIAL"EMPTY"
TOLERANCE"10%"
VOLTAGE"25V"
VALUE"0.1UF"
LOCATION"PC2366"
CDS_LIB"pure_quanta"
$SEC"1"
CDS_SEC"1";
"B"
$PN"2"28;
"A"
$PN"1"93;
%"VCC15"
"1","(-2775,-1000)","0","logical_power","I13";
;
HDL_POWER"P3V3_AUX"
CDS_LIB"logical_power";
"A"2;
%"VCC15"
"1","(-2475,-1525)","0","logical_power","I14";
;
HDL_POWER"P3V3_AUX"
CDS_LIB"logical_power";
"A"3;
%"Q_RES"
"1","(-2000,-1625)","0","pure_quanta","I15";
;
PART_NUMBER"CS21002FB06"
WATTAGE"1/16W"
MATERIAL"CHIP"
TOLERANCE"1%"
PACK_TYPE"0402LF"
VALUE"1K"
LOCATION"R2551"
CDS_LIB"pure_quanta"
LOCATION"R2551"
$SEC"1"
CDS_SEC"1";
"B"
$PN"2"47;
"A"
$PN"1"3;
%"Q_RES"
"1","(-2000,-1775)","0","pure_quanta","I16";
;
PART_NUMBER"CS00002JB13"
MATERIAL"CHIP"
PACK_TYPE"0402LF"
TOLERANCE"5%"
WATTAGE"1/16W"
VALUE"0"
LOCATION"R2552"
CDS_LIB"pure_quanta"
LOCATION"R2552"
$SEC"1"
CDS_SEC"1";
"B"
$PN"2"47;
"A"
$PN"1"43;
%"Q_RES"
"1","(-2300,-975)","0","pure_quanta","I17";
;
PART_NUMBER"CS21002FB06"
VALUE"1K"
PACK_TYPE"0402LF"
MATERIAL"CHIP"
TOLERANCE"1%"
WATTAGE"1/16W"
LOCATION"R2524"
CDS_LIB"pure_quanta"
$SEC"1"
CDS_SEC"1";
"B"
$PN"2"34;
"A"
$PN"1"2;
%"Q_RES"
"1","(-2300,-1075)","0","pure_quanta","I18";
;
PART_NUMBER"CS21002FB06"
VALUE"1K"
TOLERANCE"1%"
PACK_TYPE"0402LF"
LOCATION"R2525"
MATERIAL"CHIP"
WATTAGE"1/16W"
CDS_LIB"pure_quanta"
$SEC"1"
CDS_SEC"1";
"B"
$PN"2"36;
"A"
$PN"1"2;
%"Q_RES"
"1","(-2000,-1375)","0","pure_quanta","I19";
;
PART_NUMBER"CS00002JB13"
MATERIAL"CHIP"
PACK_TYPE"0402LF"
TOLERANCE"5%"
VALUE"0"
WATTAGE"1/16W"
LOCATION"R2550"
CDS_LIB"pure_quanta"
LOCATION"R2550"
$SEC"1"
CDS_SEC"1";
"B"
$PN"2"94;
"A"
$PN"1"42;
%"UNIVERSAL_GND"
"1","(-2600,-675)","0","logical_power","I21";
;
HDL_POWER"GND"
CDS_LIB"logical_power";
"A"11;
%"Q_SHORT"
"1","(-2875,-75)","0","pure_quanta","I22";
;
PART_NUMBER"SHORT6"
MATERIAL"EMPTY"
PACK_TYPE"SM"
LOCATION"PJ49"
NEEDS_NO_SIZE"TRUE"
CDS_LIB"pure_quanta"
LOCATION"PJ49"
$SEC"1"
CDS_SEC"1";
"1"
$PN"1"41;
"2"
$PN"2"44;
%"Q_RES"
"1","(-2800,75)","0","pure_quanta","I23";
;
PART_NUMBER"CS11002FB07"
MATERIAL"CHIP"
TOLERANCE"1%"
VALUE"100"
WATTAGE"1/16W"
PACK_TYPE"0402LF"
LOCATION"PR561"
CDS_LIB"pure_quanta"
$SEC"1"
CDS_SEC"1";
"B"
$PN"2"5;
"A"
$PN"1"41;
%"VCC15"
"1","(-2450,-575)","0","logical_power","I24";
;
HDL_POWER"P3V3_AUX"
CDS_LIB"logical_power";
"A"4;
%"Q_RES"
"1","(-2300,-675)","0","pure_quanta","I25";
;
PART_NUMBER"CS21002FB06"
VALUE"1K"
TOLERANCE"1%"
PACK_TYPE"0402LF"
LOCATION"R2522"
CDS_LIB"pure_quanta"
WATTAGE"1/16W"
MATERIAL"CHIP"
$SEC"1"
CDS_SEC"1";
"B"
$PN"2"35;
"A"
$PN"1"4;
%"UNIVERSAL_GND"
"1","(-1475,-2925)","0","logical_power","I26";
;
HDL_POWER"GND"
CDS_LIB"logical_power";
"A"12;
%"Q_RES"
"2","(-1800,-2625)","0","pure_quanta","I27";
;
PART_NUMBER"CS00002JB13"
WATTAGE"1/16W"
MATERIAL"CHIP"
TOLERANCE"5%"
PACK_TYPE"0402LF"
VALUE"0"
LOCATION"PR305"
CDS_LIB"pure_quanta"
LOCATION"PR305"
$SEC"1"
CDS_SEC"1";
"A"
$PN"1"45;
"B"
$PN"2"12;
%"Q_CAP"
"1","(-1475,-2625)","0","pure_quanta","I28";
;
PART_NUMBER"CH4104K1B00"
PACK_TYPE"0402"
MATERIAL"EMPTY"
TOLERANCE"10%"
VALUE"0.1UF"
VOLTAGE"25V"
LOCATION"PC547"
CDS_LIB"pure_quanta"
LOCATION"PC547"
$SEC"1"
CDS_SEC"1";
"B"
$PN"2"12;
"A"
$PN"1"45;
%"Q_RES"
"2","(-1050,-2625)","0","pure_quanta","I29";
;
PART_NUMBER"CS21002FB06"
WATTAGE"1/16W"
MATERIAL"EMPTY"
TOLERANCE"1%"
VALUE"1K"
PACK_TYPE"0402LF"
LOCATION"PR313"
CDS_LIB"pure_quanta"
LOCATION"PR313"
$SEC"1"
CDS_SEC"1";
"A"
$PN"1"46;
"B"
$PN"2"13;
%"UNIVERSAL_GND"
"1","(-725,-2925)","0","logical_power","I30";
;
HDL_POWER"GND"
CDS_LIB"logical_power";
"A"13;
%"Q_CAP"
"1","(-725,-2625)","0","pure_quanta","I31";
;
PART_NUMBER"CH4104K1B00"
TOLERANCE"10%"
MATERIAL"X7R"
VALUE"0.1UF"
VOLTAGE"25V"
PACK_TYPE"0402"
LOCATION"PC548"
CDS_LIB"pure_quanta"
LOCATION"PC548"
$SEC"1"
CDS_SEC"1";
"B"
$PN"2"13;
"A"
$PN"1"46;
%"UNIVERSAL_GND"
"1","(-575,-2650)","0","logical_power","I32";
;
HDL_POWER"GND"
CDS_LIB"logical_power";
"A"14;
%"RAA229126GNPHA0"
"1","(225,275)","0","pure_quanta","I33";
;
PART_NUMBER"AL229126000"
VALUE"RAA229126GNP#HA0"
MATERIAL"IC"
PART_TYPE"SMLF"
LOCATION"PU29"
CDS_LMAN_SYM_OUTLINE"-550,2850,500,-2850"
NEEDS_NO_SIZE"TRUE"
CDS_LIB"pure_quanta"
SEC_TYPE""
SEC"1";
"CS10"
$PN"28"30;
"PWM10"
$PN"11"31;
"CS9"
$PN"29"91;
"PWM9"
$PN"10"87;
"CS8"
$PN"30"88;
"PWM8"
$PN"9"86;
"CS7"
$PN"31"80;
"PWM7"
$PN"8"81;
"CS0"
$PN"38"69;
"PWM0"
$PN"1"65;
"TEMP0"
$PN"43"63;
"ADDR_CFG"
$PN"42"40;
"TH_GND"
$PN"TH"14;
"CFP"
$PN"41"34;
"CS2"
$PN"36"73;
"PWM2"
$PN"3"72;
"CS3"
$PN"35"74;
"PWM3"
$PN"4"64;
"PWM11"
$PN"12"83;
"CS1"
$PN"37"70;
"RGND1"
$PN"39"38;
"VSEN1"
$PN"40"48;
"NPINALERT||NPSYS_CRIT \B"
$PN"19"36;
"TEMP1||ISYS"
$PN"44"75;
"VINSEN||VSYS"
$PN"46"46;
"VMON||IINSEN||VSYS||ISYS"
$PN"45"45;
"VCCS"
$PN"48"92;
"PWM6"
$PN"7"79;
"PG0"
$PN"16"55;
"PWM1"
$PN"2"71;
"VSEN0"
$PN"25"90;
"PWM5"
$PN"6"82;
"PWM4"
$PN"5"66;
"PMSDA"
$PN"13"61;
"RGND0"
$PN"26"29;
"EN0"
$PN"17"62;
"NPMALERT \B"
$PN"15"60;
"SVCLK"
$PN"21"56;
"PG1"
$PN"20"47;
"CS4"
$PN"34"67;
"CS5"
$PN"33"68;
"NVRHOT \B"
$PN"18"37;
"NSVALERT \B"
$PN"23"58;
"CS6"
$PN"32"85;
"SVDATA"
$PN"22"57;
"PMSCL"
$PN"14"32;
"EN1"
$PN"24"94;
"VCC"
$PN"47"93;
"CS11"
$PN"27"84;
%"Q_CAP"
"2","(-1200,-1500)","0","pure_quanta","I34";
;
PART_NUMBER"TMP_QCH21006JB10"
VALUE"1000PF"
PACK_TYPE"0402"
VOLTAGE"50V"
MATERIAL"X7R"
TOLERANCE"5%"
LOCATION"C2446"
SEC_TYPE"0402"
CDS_LIB"pure_quanta"
LOCATION"C2446"
SEC"1";
"A"
$PN"1"94;
"B"
$PN"2"15;
%"Q_CAP"
"2","(-1200,-1625)","0","pure_quanta","I35";
;
PART_NUMBER"TMP_QCH21006JB10"
VOLTAGE"50V"
VALUE"1000PF"
PACK_TYPE"0402"
TOLERANCE"5%"
MATERIAL"EMPTY"
LOCATION"C2447"
CDS_LIB"pure_quanta"
LOCATION"C2447"
$SEC"1"
CDS_SEC"1";
"A"
$PN"1"47;
"B"
$PN"2"16;
%"Q_RES"
"1","(-1650,-825)","0","pure_quanta","I36";
;
PART_NUMBER"CS00002JB13"
VALUE"0"
TOLERANCE"5%"
PACK_TYPE"0402LF"
WATTAGE"1/16W"
MATERIAL"CHIP"
LOCATION"R2523"
CDS_LIB"pure_quanta"
$SEC"1"
CDS_SEC"1";
"B"
$PN"2"37;
"A"
$PN"1"35;
%"Q_RES"
"1","(-1775,-75)","0","pure_quanta","I37";
;
PART_NUMBER"CS00002JB13"
WATTAGE"1/16W"
MATERIAL"CHIP"
TOLERANCE"5%"
VALUE"0"
PACK_TYPE"0402LF"
LOCATION"PR242"
CDS_LIB"pure_quanta"
LOCATION"PR242"
$SEC"1"
CDS_SEC"1";
"B"
$PN"2"48;
"A"
$PN"1"44;
%"Q_CAP"
"1","(-1325,-250)","0","pure_quanta","I38";
;
PART_NUMBER"TMP_QCH2336K1B12"
VOLTAGE"50V"
MATERIAL"X7R"
PACK_TYPE"0402"
TOLERANCE"10%"
VALUE"3300PF"
LOCATION"PC422"
CDS_LIB"pure_quanta"
LOCATION"PC422"
$SEC"1"
CDS_SEC"1";
"B"
$PN"2"38;
"A"
$PN"1"48;
%"UNIVERSAL_GND"
"1","(-500,-1500)","1","logical_power","I39";
;
HDL_POWER"GND"
CDS_LIB"logical_power";
"A"15;
%"Q_RES"
"1","(-3100,-2075)","0","pure_quanta","I4";
;
PART_NUMBER"CS32802FB05"
TOLERANCE"1%"
MATERIAL"EMPTY"
VALUE"28K"
WATTAGE"1/16W"
PACK_TYPE"0402LF"
LOCATION"PR306"
CDS_LIB"pure_quanta"
LOCATION"PR306"
$SEC"1"
CDS_SEC"1";
"B"
$PN"2"40;
"A"
$PN"1"39;
%"UNIVERSAL_GND"
"1","(-500,-1625)","1","logical_power","I40";
;
HDL_POWER"GND"
CDS_LIB"logical_power";
"A"16;
%"Q_RES"
"1","(-2850,500)","0","pure_quanta","I45";
;
PART_NUMBER"CS11002FB07"
VALUE"100"
MATERIAL"CHIP"
TOLERANCE"1%"
WATTAGE"1/16W"
PACK_TYPE"0402LF"
LOCATION"PR574"
CDS_LIB"pure_quanta"
$SEC"1"
CDS_SEC"1";
"B"
$PN"2"17;
"A"
$PN"1"29;
%"Q_SHORT"
"1","(-2875,1025)","0","pure_quanta","I46";
;
PART_NUMBER"SHORT6"
PACK_TYPE"SM"
MATERIAL"EMPTY"
LOCATION"PJ52"
NEEDS_NO_SIZE"TRUE"
CDS_LIB"pure_quanta"
LOCATION"PJ52"
$SEC"1"
CDS_SEC"1";
"1"
$PN"1"49;
"2"
$PN"2"89;
%"UNIVERSAL_GND"
"1","(-2325,400)","0","logical_power","I47";
;
HDL_POWER"GND"
CDS_LIB"logical_power";
"A"17;
%"VCC15"
"1","(-2300,225)","0","logical_power","I48";
;
HDL_POWER"PVCCFA_EHV_FIVRA_CPU1"
CDS_LIB"logical_power";
"A"5;
%"Q_RES"
"1","(-2800,1175)","0","pure_quanta","I49";
;
PART_NUMBER"CS11002FB07"
MATERIAL"CHIP"
VALUE"100"
TOLERANCE"1%"
WATTAGE"1/16W"
PACK_TYPE"0402LF"
LOCATION"PR578"
CDS_LIB"pure_quanta"
$SEC"1"
CDS_SEC"1";
"B"
$PN"2"6;
"A"
$PN"1"49;
%"UNIVERSAL_GND"
"1","(-2725,-2525)","0","logical_power","I5";
;
HDL_POWER"GND"
CDS_LIB"logical_power";
"A"10;
%"VCC15"
"1","(-2300,1325)","0","logical_power","I50";
;
HDL_POWER"PVCCIN_CPU1"
CDS_LIB"logical_power";
"A"6;
%"Q_RES"
"1","(-2175,2425)","0","pure_quanta","I56";
;
PART_NUMBER"CS00002JB13"
PACK_TYPE"0402LF"
WATTAGE"1/16W"
TOLERANCE"5%"
MATERIAL"CHIP"
VALUE"0"
LOCATION"R311"
CDS_LIB"pure_quanta"
LOCATION"R311"
$SEC"1"
CDS_SEC"1";
"B"
$PN"2"57;
"A"
$PN"1"54;
%"Q_RES"
"1","(-2175,2275)","0","pure_quanta","I57";
;
PART_NUMBER"CS00002JB13"
WATTAGE"1/16W"
MATERIAL"CHIP"
VALUE"0"
PACK_TYPE"0402LF"
TOLERANCE"5%"
LOCATION"R312"
CDS_LIB"pure_quanta"
LOCATION"R312"
$SEC"1"
CDS_SEC"1";
"B"
$PN"2"58;
"A"
$PN"1"50;
%"Q_RES"
"1","(-2175,2575)","0","pure_quanta","I58";
;
PART_NUMBER"CS11502FB07"
WATTAGE"1/16W"
MATERIAL"CHIP"
PACK_TYPE"0402LF"
TOLERANCE"1%"
VALUE"150"
LOCATION"R310"
CDS_LIB"pure_quanta"
LOCATION"R310"
$SEC"1"
CDS_SEC"1";
"B"
$PN"2"56;
"A"
$PN"1"53;
%"Q_RES"
"1","(-2175,2875)","0","pure_quanta","I59";
;
PART_NUMBER"CS00002JB13"
MATERIAL"CHIP"
VALUE"0"
PACK_TYPE"0402LF"
TOLERANCE"5%"
WATTAGE"1/16W"
LOCATION"R309"
CDS_LIB"pure_quanta"
LOCATION"R309"
$SEC"1"
CDS_SEC"1";
"B"
$PN"2"62;
"A"
$PN"1"52;
%"Q_RES"
"2","(-2725,-2300)","2","pure_quanta","I6";
;
PART_NUMBER"CS25232FB08"
PACK_TYPE"0402LF"
VALUE"5.23K"
MATERIAL"CHIP"
TOLERANCE"1%"
WATTAGE"1/16W"
LOCATION"PR318"
CDS_LIB"pure_quanta"
LOCATION"PR318"
$SEC"1"
CDS_SEC"1";
"A"
$PN"1"40;
"B"
$PN"2"10;
%"Q_RES"
"1","(-2175,3025)","0","pure_quanta","I60";
;
PART_NUMBER"CS00002JB13"
MATERIAL"CHIP"
TOLERANCE"5%"
VALUE"0"
PACK_TYPE"0402LF"
WATTAGE"1/16W"
LOCATION"R308"
CDS_LIB"pure_quanta"
LOCATION"R308"
$SEC"1"
CDS_SEC"1";
"B"
$PN"2"55;
"A"
$PN"1"51;
%"Q_RES"
"1","(-2175,3175)","0","pure_quanta","I61";
;
PART_NUMBER"CS21002FB06"
WATTAGE"1/16W"
VALUE"1K"
TOLERANCE"1%"
PACK_TYPE"0402LF"
MATERIAL"CHIP"
LOCATION"R307"
CDS_LIB"pure_quanta"
LOCATION"R307"
$SEC"1"
CDS_SEC"1";
"B"
$PN"2"55;
"A"
$PN"1"7;
%"VCC15"
"1","(-2600,3275)","0","logical_power","I62";
;
HDL_POWER"P3V3_AUX"
CDS_LIB"logical_power";
"A"7;
%"Q_RES"
"1","(-1825,1025)","0","pure_quanta","I63";
;
PART_NUMBER"CS00002JB13"
WATTAGE"1/16W"
MATERIAL"CHIP"
PACK_TYPE"0402LF"
TOLERANCE"5%"
VALUE"0"
LOCATION"PR317"
CDS_LIB"pure_quanta"
LOCATION"PR317"
$SEC"1"
CDS_SEC"1";
"B"
$PN"2"90;
"A"
$PN"1"89;
%"Q_CAP"
"1","(-1375,850)","0","pure_quanta","I64";
;
PART_NUMBER"TMP_QCH2336K1B12"
MATERIAL"X7R"
TOLERANCE"10%"
PACK_TYPE"0402"
VALUE"3300PF"
VOLTAGE"50V"
LOCATION"PC549"
CDS_LIB"pure_quanta"
LOCATION"PC549"
$SEC"1"
CDS_SEC"1";
"B"
$PN"2"29;
"A"
$PN"1"90;
%"Q_RES"
"1","(-1850,1875)","0","pure_quanta","I65";
;
PART_NUMBER"CS00002JB13"
MATERIAL"CHIP"
WATTAGE"1/16W"
VALUE"0"
TOLERANCE"5%"
PACK_TYPE"0402LF"
LOCATION"R2520"
CDS_LIB"pure_quanta"
LOCATION"R2520"
$SEC"1"
CDS_SEC"1";
"B"
$PN"2"32;
"A"
$PN"1"33;
%"Q_RES"
"1","(-1850,1725)","0","pure_quanta","I66";
;
PART_NUMBER"CS00002JB13"
PACK_TYPE"0402LF"
WATTAGE"1/16W"
MATERIAL"CHIP"
TOLERANCE"5%"
VALUE"0"
LOCATION"R2521"
CDS_LIB"pure_quanta"
LOCATION"R2521"
$SEC"1"
CDS_SEC"1";
"B"
$PN"2"61;
"A"
$PN"1"59;
%"Q_CAP"
"2","(-1350,2750)","0","pure_quanta","I67";
;
PART_NUMBER"TMP_QCH21006JB10"
TOLERANCE"5%"
MATERIAL"X7R"
VOLTAGE"50V"
VALUE"1000PF"
PACK_TYPE"0402"
LOCATION"C2860"
CDS_LIB"pure_quanta"
LOCATION"C2860"
$SEC"1"
CDS_SEC"1";
"A"
$PN"1"62;
"B"
$PN"2"18;
%"Q_CAP"
"2","(-1325,3175)","0","pure_quanta","I68";
;
PART_NUMBER"TMP_QCH21006JB10"
MATERIAL"EMPTY"
VOLTAGE"50V"
VALUE"1000PF"
PACK_TYPE"0402"
TOLERANCE"5%"
LOCATION"C2859"
CDS_LIB"pure_quanta"
LOCATION"C2859"
$SEC"1"
CDS_SEC"1";
"A"
$PN"1"55;
"B"
$PN"2"19;
%"UNIVERSAL_GND"
"1","(-625,2750)","1","logical_power","I69";
;
HDL_POWER"GND"
CDS_LIB"logical_power";
"A"18;
%"Q_RES"
"1","(-2250,-2425)","0","pure_quanta","I7";
;
PART_NUMBER"CS00002JB13"
VALUE"0"
TOLERANCE"5%"
WATTAGE"1/16W"
MATERIAL"CHIP"
PACK_TYPE"0402LF"
LOCATION"PR303"
CDS_LIB"pure_quanta"
LOCATION"PR303"
$SEC"1"
CDS_SEC"1";
"B"
$PN"2"46;
"A"
$PN"1"1;
%"UNIVERSAL_GND"
"1","(-625,3175)","1","logical_power","I70";
;
HDL_POWER"GND"
CDS_LIB"logical_power";
"A"19;
%"UNIVERSAL_GND"
"1","(1200,-2600)","0","logical_power","I71";
;
HDL_POWER"GND"
CDS_LIB"logical_power";
"A"20;
%"Q_CAP"
"1","(1200,-2375)","0","pure_quanta","I72";
;
PART_NUMBER"TMP_QCH14706KB18"
TOLERANCE"10%"
VALUE"470PF"
VOLTAGE"50V"
PACK_TYPE"0402"
MATERIAL"X7R"
LOCATION"PC554"
CDS_LIB"pure_quanta"
LOCATION"PC554"
$SEC"1"
CDS_SEC"1";
"B"
$PN"2"20;
"A"
$PN"1"63;
%"UNIVERSAL_GND"
"1","(1850,-2625)","0","logical_power","I73";
;
HDL_POWER"GND"
CDS_LIB"logical_power";
"A"21;
%"Q_RES"
"2","(1850,-2375)","0","pure_quanta","I74";
;
PART_NUMBER"CS31002FB08"
WATTAGE"1/16W"
PACK_TYPE"0402LF"
TOLERANCE"1%"
VALUE"10K"
MATERIAL"EMPTY"
LOCATION"PR637"
CDS_LIB"pure_quanta"
$SEC"1"
CDS_SEC"1";
"A"
$PN"1"63;
"B"
$PN"2"21;
%"UNIVERSAL_GND"
"1","(1900,-925)","0","logical_power","I77";
;
HDL_POWER"GND"
CDS_LIB"logical_power";
"A"22;
%"VCC15"
"1","(-2525,-2200)","0","logical_power","I8";
;
HDL_POWER"P12V_AUX"
CDS_LIB"logical_power";
"A"1;
%"Q_RES"
"1","(1275,-850)","0","pure_quanta","I80";
;
PART_NUMBER"CS00002JB13"
VALUE"0"
TOLERANCE"5%"
MATERIAL"EMPTY"
LOCATION"PR4239"
PACK_TYPE"0402LF"
WATTAGE"1/16W"
CDS_LIB"pure_quanta"
$SEC"1"
CDS_SEC"1";
"B"
$PN"2"22;
"A"
$PN"1"73;
%"Q_RES"
"1","(1275,-550)","0","pure_quanta","I81";
;
PART_NUMBER"CS00002JB13"
VALUE"0"
TOLERANCE"5%"
MATERIAL"EMPTY"
LOCATION"PR4238"
WATTAGE"1/16W"
PACK_TYPE"0402LF"
CDS_LIB"pure_quanta"
$SEC"1"
CDS_SEC"1";
"B"
$PN"2"23;
"A"
$PN"1"74;
%"UNIVERSAL_GND"
"1","(1900,-625)","0","logical_power","I82";
;
HDL_POWER"GND"
CDS_LIB"logical_power";
"A"23;
%"Q_RES"
"1","(-2250,-2325)","0","pure_quanta","I9";
;
PART_NUMBER"CS00002JB13"
PACK_TYPE"0402LF"
MATERIAL"EMPTY"
TOLERANCE"5%"
VALUE"0"
LOCATION"PR304"
CDS_LIB"pure_quanta"
WATTAGE"1/16W"
LOCATION"PR304"
$SEC"1"
CDS_SEC"1";
"B"
$PN"2"45;
"A"
$PN"1"1;
%"UNIVERSAL_GND"
"1","(2875,-2300)","0","logical_power","I91";
;
HDL_POWER"GND"
CDS_LIB"logical_power";
"A"24;
%"Q_CAP"
"1","(2875,-2075)","0","pure_quanta","I92";
;
PART_NUMBER"TMP_QCH14706KB18"
VALUE"470PF"
PACK_TYPE"0402"
VOLTAGE"50V"
TOLERANCE"10%"
MATERIAL"X7R"
LOCATION"PC101"
CDS_LIB"pure_quanta"
LOCATION"PC101"
$SEC"1"
CDS_SEC"1";
"B"
$PN"2"24;
"A"
$PN"1"75;
%"UNIVERSAL_GND"
"1","(3575,-2325)","0","logical_power","I93";
;
HDL_POWER"GND"
CDS_LIB"logical_power";
"A"25;
%"Q_RES"
"2","(3575,-2100)","0","pure_quanta","I94";
;
PART_NUMBER"CS31002FB08"
MATERIAL"EMPTY"
WATTAGE"1/16W"
VALUE"10K"
TOLERANCE"1%"
PACK_TYPE"0402LF"
LOCATION"PR453"
CDS_LIB"pure_quanta"
$SEC"1"
CDS_SEC"1";
"A"
$PN"1"75;
"B"
$PN"2"25;
%"Q_RES"
"1","(3925,-925)","0","pure_quanta","I99";
;
PART_NUMBER"CS11002FB07"
PACK_TYPE"0402LF"
MATERIAL"CHIP"
TOLERANCE"1%"
VALUE"100"
WATTAGE"1/16W"
LOCATION"R2553"
CDS_LIB"pure_quanta"
$SEC"1"
CDS_SEC"1";
"B"
$PN"2"8;
"A"
$PN"1"76;
END.
